(kicad_pcb
	(version 20260206)
	(generator "pcbnew")
	(generator_version "10.0")
	(general
		(thickness 1.6)
		(legacy_teardrops no)
	)
	(paper "A4")
	(title_block
		(title "04192023_DAF0TMB3IC0_F0TG_MB_C_brd_V02_OCP.brd")
		(comment 1 "Grand Teton / footprints 5278-5283 of 8354")
	)
	(layers
		(0 "F.Cu" signal "TOP")
		(4 "In1.Cu" signal "GND")
		(6 "In2.Cu" signal "IN1")
		(8 "In3.Cu" signal "GND1")
		(10 "In4.Cu" signal "IN2")
		(12 "In5.Cu" signal "GND2")
		(14 "In6.Cu" signal "IN3")
		(16 "In7.Cu" signal "GND3")
		(18 "In8.Cu" signal "VCC")
		(20 "In9.Cu" signal "VCC1")
		(22 "In10.Cu" signal "GND4")
		(24 "In11.Cu" signal "IN4")
		(26 "In12.Cu" signal "GND5")
		(28 "In13.Cu" signal "IN5")
		(30 "In14.Cu" signal "GND6")
		(32 "In15.Cu" signal "IN6")
		(34 "In16.Cu" signal "GND7")
		(2 "B.Cu" signal "BOTTOM")
		(9 "F.Adhes" user "F.Adhesive")
		(11 "B.Adhes" user "B.Adhesive")
		(13 "F.Paste" user "Package Geometry/Pastemask Top")
		(15 "B.Paste" user "Package Geometry/Pastemask Bottom")
		(5 "F.SilkS" user "Ref Des/Silkscreen Top")
		(7 "B.SilkS" user "Ref Des/Silkscreen Bottom")
		(1 "F.Mask" user "Board Geometry/Soldermask Top")
		(3 "B.Mask" user "Board Geometry/Soldermask Bottom")
		(17 "Dwgs.User" user "User.Drawings")
		(19 "Cmts.User" user "User.Comments")
		(21 "Eco1.User" user "User.Eco1")
		(23 "Eco2.User" user "User.Eco2")
		(25 "Edge.Cuts" user "Board Geometry/Outline")
		(27 "Margin" user)
		(31 "F.CrtYd" user "Package Geometry/Place Bound Top")
		(29 "B.CrtYd" user "Package Geometry/Place Bound Bottom")
		(35 "F.Fab" user "Ref Des/Assembly Top")
		(33 "B.Fab" user "Ref Des/Assembly Bottom")
	)
	(footprint ""
		(layer "B.Cu")
		(at 511.924808 -298.345606 -90)
		(property "Reference" "X27"
			(at 3.097276 3.214878 270)
			(unlocked yes)
			(layer "B.SilkS")
			(effects
				(font
					(size 0.7874 0.5842)
					(thickness 0.1524)
				)
				(justify left mirror)
			)
		)
		(property "Value" ""
			(at 0 0 90)
			(layer "B.Fab")
			(effects
				(font
					(size 1.27 1.27)
				)
				(justify mirror)
			)
		)
		(property "User Part Number" "N_A"
			(at -1.30175 1.27 180)
			(unlocked yes)
			(layer "Cmts.User")
			(hide yes)
			(effects
				(font
					(size 0.635 0.4064)
					(thickness 0.1524)
				)
				(justify mirror)
			)
		)
		(property "Device Type" "TP_TDR_4P_FTS_TH-TP_TDR_4P_DIP,EMPTY,TP15"
			(at -1.30175 1.27 180)
			(unlocked yes)
			(layer "B.Fab")
			(hide yes)
			(effects
				(font
					(size 0.635 0.4064)
					(thickness 0.1524)
				)
				(justify mirror)
			)
		)
		(duplicate_pad_numbers_are_jumpers no)
		(fp_line
			(start -2.54 3.81)
			(end -2.54 3.6703)
			(stroke
				(width 0.1524)
				(type default)
			)
			(layer "B.SilkS")
		)
		(fp_line
			(start 0 3.81)
			(end -2.54 3.81)
			(stroke
				(width 0.1524)
				(type default)
			)
			(layer "B.SilkS")
		)
		(fp_line
			(start 0 3.175)
			(end 0 3.81)
			(stroke
				(width 0.1524)
				(type default)
			)
			(layer "B.SilkS")
		)
		(fp_line
			(start -2.54 1.4097)
			(end -2.54 1.1303)
			(stroke
				(width 0.1524)
				(type default)
			)
			(layer "B.SilkS")
		)
		(fp_line
			(start 0 0.635)
			(end 0 1.905)
			(stroke
				(width 0.1524)
				(type default)
			)
			(layer "B.SilkS")
		)
		(fp_line
			(start -2.54 -1.1303)
			(end -2.54 -1.27)
			(stroke
				(width 0.1524)
				(type default)
			)
			(layer "B.SilkS")
		)
		(fp_line
			(start -2.54 -1.27)
			(end 0 -1.27)
			(stroke
				(width 0.1524)
				(type default)
			)
			(layer "B.SilkS")
		)
		(fp_line
			(start 0 -1.27)
			(end 0 -0.635)
			(stroke
				(width 0.1524)
				(type default)
			)
			(layer "B.SilkS")
		)
		(fp_poly
			(pts
				(xy 2.285746 -0.762) (xy 2.285746 0.762) (xy 0.761746 0)
			)
			(stroke
				(width 0)
				(type default)
			)
			(fill yes)
			(layer "B.SilkS")
		)
		(fp_line
			(start -2.54 3.81)
			(end -2.54 -1.27)
			(stroke
				(width 0.1)
				(type default)
			)
			(layer "B.Fab")
		)
		(fp_line
			(start 0 3.81)
			(end -2.54 3.81)
			(stroke
				(width 0.1)
				(type default)
			)
			(layer "B.Fab")
		)
		(fp_line
			(start -2.54 -1.27)
			(end 0 -1.27)
			(stroke
				(width 0.1)
				(type default)
			)
			(layer "B.Fab")
		)
		(fp_line
			(start 0 -1.27)
			(end 0 3.81)
			(stroke
				(width 0.1)
				(type default)
			)
			(layer "B.Fab")
		)
		(fp_poly
			(pts
				(xy 0.761746 0) (xy 2.285746 -0.762) (xy 2.285746 0.762)
			)
			(stroke
				(width 0)
				(type default)
			)
			(fill yes)
			(layer "B.Fab")
		)
		(pad "1" thru_hole circle
			(at 0 0 90)
			(size 1.0033 1.0033)
			(drill 0.249936)
			(layers "*.Cu" "*.Mask")
			(remove_unused_layers no)
			(net "TDR_DIFF_80_IN5_DN")
			(clearance 0.10795)
			(padstack
				(mode front_inner_back)
				(layer "Inner"
					(shape circle)
					(size 0.8001 0.8001)
					(clearance 0.1524)
				)
				(layer "B.Cu"
					(shape circle)
					(size 1.0033 1.0033)
					(thermal_gap 0.10795)
					(clearance 0.10795)
				)
			)
		)
		(pad "2" thru_hole circle
			(at -2.54 0 90)
			(size 1.9939 1.9939)
			(drill 0.249936)
			(layers "*.Cu" "*.Mask")
			(remove_unused_layers no)
			(net "T1_GND")
			(clearance 0.10795)
			(padstack
				(mode front_inner_back)
				(layer "Inner"
					(shape circle)
					(size 0.8001 0.8001)
					(clearance 0.1524)
				)
				(layer "B.Cu"
					(shape circle)
					(size 1.9939 1.9939)
					(thermal_gap 0.10795)
					(clearance 0.10795)
				)
			)
		)
		(pad "3" thru_hole circle
			(at -2.54 2.54 90)
			(size 1.9939 1.9939)
			(drill 0.249936)
			(layers "*.Cu" "*.Mask")
			(remove_unused_layers no)
			(net "T1_GND")
			(clearance 0.10795)
			(padstack
				(mode front_inner_back)
				(layer "Inner"
					(shape circle)
					(size 0.8001 0.8001)
					(clearance 0.1524)
				)
				(layer "B.Cu"
					(shape circle)
					(size 1.9939 1.9939)
					(thermal_gap 0.10795)
					(clearance 0.10795)
				)
			)
		)
		(pad "4" thru_hole circle
			(at 0 2.54 90)
			(size 1.0033 1.0033)
			(drill 0.249936)
			(layers "*.Cu" "*.Mask")
			(remove_unused_layers no)
			(net "TDR_DIFF_80_IN5_DP")
			(clearance 0.10795)
			(padstack
				(mode front_inner_back)
				(layer "Inner"
					(shape circle)
					(size 0.8001 0.8001)
					(clearance 0.1524)
				)
				(layer "B.Cu"
					(shape circle)
					(size 1.0033 1.0033)
					(thermal_gap 0.10795)
					(clearance 0.10795)
				)
			)
		)
	)
	(footprint ""
		(layer "B.Cu")
		(at 284.736286 -192.660016)
		(property "Reference" "C150"
			(at 0 0 0)
			(layer "B.SilkS")
			(hide yes)
			(effects
				(font
					(size 1.27 1.27)
				)
				(justify mirror)
			)
		)
		(property "Value" ""
			(at 0 0 0)
			(layer "B.Fab")
			(effects
				(font
					(size 1.27 1.27)
				)
				(justify mirror)
			)
		)
		(duplicate_pad_numbers_are_jumpers no)
		(fp_line
			(start -1.524 -0.762)
			(end -1.524 0.762)
			(stroke
				(width 0.1524)
				(type default)
			)
			(layer "B.SilkS")
		)
		(fp_line
			(start -1.524 0.762)
			(end 1.524 0.762)
			(stroke
				(width 0.1524)
				(type default)
			)
			(layer "B.SilkS")
		)
		(fp_line
			(start 1.524 -0.762)
			(end -1.524 -0.762)
			(stroke
				(width 0.1524)
				(type default)
			)
			(layer "B.SilkS")
		)
		(fp_line
			(start 1.524 0.762)
			(end 1.524 -0.762)
			(stroke
				(width 0.1524)
				(type default)
			)
			(layer "B.SilkS")
		)
		(fp_line
			(start -1.1049 -0.724916)
			(end 1.1049 -0.724916)
			(stroke
				(width 0.1)
				(type default)
			)
			(layer "B.Fab")
		)
		(fp_line
			(start -1.1049 0.724916)
			(end -1.1049 -0.724916)
			(stroke
				(width 0.1)
				(type default)
			)
			(layer "B.Fab")
		)
		(fp_line
			(start 1.1049 -0.724916)
			(end 1.1049 0.724916)
			(stroke
				(width 0.1)
				(type default)
			)
			(layer "B.Fab")
		)
		(fp_line
			(start 1.1049 0.724916)
			(end -1.1049 0.724916)
			(stroke
				(width 0.1)
				(type default)
			)
			(layer "B.Fab")
		)
		(pad "1" smd rect
			(at 0.889 0)
			(size 1.016 1.27)
			(layers "B.Cu" "B.Mask" "B.Paste")
			(net "P12V_MEM_CPU0")
		)
		(pad "2" smd rect
			(at -0.889 0)
			(size 1.016 1.27)
			(layers "B.Cu" "B.Mask" "B.Paste")
			(net "GND")
		)
	)
	(footprint ""
		(layer "B.Cu")
		(at 376.491246 -398.942052 90)
		(property "Reference" "C1038"
			(at 0 0 90)
			(layer "B.SilkS")
			(hide yes)
			(effects
				(font
					(size 1.27 1.27)
				)
				(justify mirror)
			)
		)
		(property "Value" ""
			(at 0 0 90)
			(layer "B.Fab")
			(effects
				(font
					(size 1.27 1.27)
				)
				(justify mirror)
			)
		)
		(duplicate_pad_numbers_are_jumpers no)
		(fp_line
			(start 0.7874 -0.4064)
			(end -0.7874 -0.4064)
			(stroke
				(width 0.1524)
				(type default)
			)
			(layer "B.SilkS")
		)
		(fp_line
			(start -0.7874 -0.4064)
			(end -0.7874 0.4064)
			(stroke
				(width 0.1524)
				(type default)
			)
			(layer "B.SilkS")
		)
		(fp_line
			(start 0.7874 0.4064)
			(end 0.7874 -0.4064)
			(stroke
				(width 0.1524)
				(type default)
			)
			(layer "B.SilkS")
		)
		(fp_line
			(start -0.7874 0.4064)
			(end 0.7874 0.4064)
			(stroke
				(width 0.1524)
				(type default)
			)
			(layer "B.SilkS")
		)
		(fp_line
			(start 0.67945 -0.305054)
			(end 0.12065 -0.305054)
			(stroke
				(width 0.1)
				(type default)
			)
			(layer "B.Fab")
		)
		(fp_line
			(start 0.12065 -0.305054)
			(end 0.12065 -0.2794)
			(stroke
				(width 0.1)
				(type default)
			)
			(layer "B.Fab")
		)
		(fp_line
			(start -0.12065 -0.3048)
			(end -0.67945 -0.3048)
			(stroke
				(width 0.1)
				(type default)
			)
			(layer "B.Fab")
		)
		(fp_line
			(start -0.67945 -0.3048)
			(end -0.67945 0.3048)
			(stroke
				(width 0.1)
				(type default)
			)
			(layer "B.Fab")
		)
		(fp_line
			(start 0.12065 -0.2794)
			(end -0.12065 -0.2794)
			(stroke
				(width 0.1)
				(type default)
			)
			(layer "B.Fab")
		)
		(fp_line
			(start -0.12065 -0.2794)
			(end -0.12065 -0.3048)
			(stroke
				(width 0.1)
				(type default)
			)
			(layer "B.Fab")
		)
		(fp_line
			(start 0.12065 0.2794)
			(end 0.12065 0.3048)
			(stroke
				(width 0.1)
				(type default)
			)
			(layer "B.Fab")
		)
		(fp_line
			(start -0.120396 0.2794)
			(end 0.12065 0.2794)
			(stroke
				(width 0.1)
				(type default)
			)
			(layer "B.Fab")
		)
		(fp_line
			(start 0.67945 0.3048)
			(end 0.67945 -0.305054)
			(stroke
				(width 0.1)
				(type default)
			)
			(layer "B.Fab")
		)
		(fp_line
			(start 0.12065 0.3048)
			(end 0.67945 0.3048)
			(stroke
				(width 0.1)
				(type default)
			)
			(layer "B.Fab")
		)
		(fp_line
			(start -0.120396 0.3048)
			(end -0.120396 0.2794)
			(stroke
				(width 0.1)
				(type default)
			)
			(layer "B.Fab")
		)
		(fp_line
			(start -0.67945 0.3048)
			(end -0.120396 0.3048)
			(stroke
				(width 0.1)
				(type default)
			)
			(layer "B.Fab")
		)
		(pad "1" smd circle
			(at 0.40005 0 270)
			(size 0 0)
			(layers "B.Cu" "B.Mask" "B.Paste")
			(net "P0V9_CPU0_RT_2D")
		)
		(pad "2" smd circle
			(at -0.40005 0 270)
			(size 0 0)
			(layers "B.Cu" "B.Mask" "B.Paste")
			(net "GND")
		)
	)
	(footprint ""
		(layer "B.Cu")
		(at 182.732172 -111.863124 -90)
		(property "Reference" "C1127"
			(at 0 0 90)
			(layer "B.SilkS")
			(hide yes)
			(effects
				(font
					(size 1.27 1.27)
				)
				(justify mirror)
			)
		)
		(property "Value" ""
			(at 0 0 90)
			(layer "B.Fab")
			(effects
				(font
					(size 1.27 1.27)
				)
				(justify mirror)
			)
		)
		(duplicate_pad_numbers_are_jumpers no)
		(fp_line
			(start -0.69215 0.2921)
			(end 0.69215 0.2921)
			(stroke
				(width 0.1524)
				(type default)
			)
			(layer "B.SilkS")
		)
		(fp_line
			(start 0.69215 0.2921)
			(end 0.69215 -0.2921)
			(stroke
				(width 0.1524)
				(type default)
			)
			(layer "B.SilkS")
		)
		(fp_line
			(start -0.69215 -0.2921)
			(end -0.69215 0.2921)
			(stroke
				(width 0.1524)
				(type default)
			)
			(layer "B.SilkS")
		)
		(fp_line
			(start 0.69215 -0.2921)
			(end -0.69215 -0.2921)
			(stroke
				(width 0.1524)
				(type default)
			)
			(layer "B.SilkS")
		)
		(fp_line
			(start -0.51435 0.2794)
			(end 0.51435 0.2794)
			(stroke
				(width 0.1)
				(type default)
			)
			(layer "B.Fab")
		)
		(fp_line
			(start 0.51435 0.2794)
			(end 0.51435 -0.2794)
			(stroke
				(width 0.1)
				(type default)
			)
			(layer "B.Fab")
		)
		(fp_line
			(start -0.51435 -0.2794)
			(end -0.51435 0.2794)
			(stroke
				(width 0.1)
				(type default)
			)
			(layer "B.Fab")
		)
		(fp_line
			(start 0.51435 -0.2794)
			(end -0.51435 -0.2794)
			(stroke
				(width 0.1)
				(type default)
			)
			(layer "B.Fab")
		)
		(pad "1" smd circle
			(at 0.40005 0 90)
			(size 0 0)
			(layers "B.Cu" "B.Mask" "B.Paste")
			(net "P1V8_AUX")
		)
		(pad "2" smd circle
			(at -0.40005 0 90)
			(size 0 0)
			(layers "B.Cu" "B.Mask" "B.Paste")
			(net "GND")
		)
		(zone
			(layer "B.Cu")
			(hatch none 0.5)
			(connect_pads
				(clearance 0)
			)
			(min_thickness 0.25)
			(keepout
				(tracks not_allowed)
				(vias allowed)
				(pads allowed)
				(copperpour not_allowed)
				(footprints allowed)
			)
			(placement
				(enabled no)
				(sheetname "")
			)
			(fill
				(thermal_gap 0.5)
				(thermal_bridge_width 0.5)
				(island_removal_mode 0)
			)
			(polygon
				(pts
					(xy 182.586376 -111.764064) (xy 182.586376 -111.963454) (xy 182.644542 -112.053624) (xy 182.819802 -112.053624)
					(xy 182.878222 -111.963454) (xy 182.878222 -111.764064) (xy 182.820056 -111.672624) (xy 182.644542 -111.672624)
				)
			)
		)
	)
	(footprint ""
		(layer "B.Cu")
		(at 90.719148 -390.560052 90)
		(property "Reference" "C327"
			(at 0 0 90)
			(layer "B.SilkS")
			(hide yes)
			(effects
				(font
					(size 1.27 1.27)
				)
				(justify mirror)
			)
		)
		(property "Value" ""
			(at 0 0 90)
			(layer "B.Fab")
			(effects
				(font
					(size 1.27 1.27)
				)
				(justify mirror)
			)
		)
		(duplicate_pad_numbers_are_jumpers no)
		(fp_line
			(start 0.7874 -0.4064)
			(end -0.7874 -0.4064)
			(stroke
				(width 0.1524)
				(type default)
			)
			(layer "B.SilkS")
		)
		(fp_line
			(start -0.7874 -0.4064)
			(end -0.7874 0.4064)
			(stroke
				(width 0.1524)
				(type default)
			)
			(layer "B.SilkS")
		)
		(fp_line
			(start 0.7874 0.4064)
			(end 0.7874 -0.4064)
			(stroke
				(width 0.1524)
				(type default)
			)
			(layer "B.SilkS")
		)
		(fp_line
			(start -0.7874 0.4064)
			(end 0.7874 0.4064)
			(stroke
				(width 0.1524)
				(type default)
			)
			(layer "B.SilkS")
		)
		(fp_line
			(start 0.67945 -0.305054)
			(end 0.12065 -0.305054)
			(stroke
				(width 0.1)
				(type default)
			)
			(layer "B.Fab")
		)
		(fp_line
			(start 0.12065 -0.305054)
			(end 0.12065 -0.2794)
			(stroke
				(width 0.1)
				(type default)
			)
			(layer "B.Fab")
		)
		(fp_line
			(start -0.12065 -0.3048)
			(end -0.67945 -0.3048)
			(stroke
				(width 0.1)
				(type default)
			)
			(layer "B.Fab")
		)
		(fp_line
			(start -0.67945 -0.3048)
			(end -0.67945 0.3048)
			(stroke
				(width 0.1)
				(type default)
			)
			(layer "B.Fab")
		)
		(fp_line
			(start 0.12065 -0.2794)
			(end -0.12065 -0.2794)
			(stroke
				(width 0.1)
				(type default)
			)
			(layer "B.Fab")
		)
		(fp_line
			(start -0.12065 -0.2794)
			(end -0.12065 -0.3048)
			(stroke
				(width 0.1)
				(type default)
			)
			(layer "B.Fab")
		)
		(fp_line
			(start 0.12065 0.2794)
			(end 0.12065 0.3048)
			(stroke
				(width 0.1)
				(type default)
			)
			(layer "B.Fab")
		)
		(fp_line
			(start -0.120396 0.2794)
			(end 0.12065 0.2794)
			(stroke
				(width 0.1)
				(type default)
			)
			(layer "B.Fab")
		)
		(fp_line
			(start 0.67945 0.3048)
			(end 0.67945 -0.305054)
			(stroke
				(width 0.1)
				(type default)
			)
			(layer "B.Fab")
		)
		(fp_line
			(start 0.12065 0.3048)
			(end 0.67945 0.3048)
			(stroke
				(width 0.1)
				(type default)
			)
			(layer "B.Fab")
		)
		(fp_line
			(start -0.120396 0.3048)
			(end -0.120396 0.2794)
			(stroke
				(width 0.1)
				(type default)
			)
			(layer "B.Fab")
		)
		(fp_line
			(start -0.67945 0.3048)
			(end -0.120396 0.3048)
			(stroke
				(width 0.1)
				(type default)
			)
			(layer "B.Fab")
		)
		(pad "1" smd circle
			(at 0.40005 0 270)
			(size 0 0)
			(layers "B.Cu" "B.Mask" "B.Paste")
			(net "P0V9_CPU1_RT_2D")
		)
		(pad "2" smd circle
			(at -0.40005 0 270)
			(size 0 0)
			(layers "B.Cu" "B.Mask" "B.Paste")
			(net "GND")
		)
	)
	(footprint ""
		(layer "B.Cu")
		(at 397.637508 -341.168736 -90)
		(property "Reference" "R942"
			(at 0 0 90)
			(layer "B.SilkS")
			(hide yes)
			(effects
				(font
					(size 1.27 1.27)
				)
				(justify mirror)
			)
		)
		(property "Value" ""
			(at 0 0 90)
			(layer "B.Fab")
			(effects
				(font
					(size 1.27 1.27)
				)
				(justify mirror)
			)
		)
		(duplicate_pad_numbers_are_jumpers no)
		(fp_line
			(start -0.7874 0.4064)
			(end 0.7874 0.4064)
			(stroke
				(width 0.1524)
				(type default)
			)
			(layer "B.SilkS")
		)
		(fp_line
			(start 0.7874 0.4064)
			(end 0.7874 -0.4064)
			(stroke
				(width 0.1524)
				(type default)
			)
			(layer "B.SilkS")
		)
		(fp_line
			(start -0.7874 -0.4064)
			(end -0.7874 0.4064)
			(stroke
				(width 0.1524)
				(type default)
			)
			(layer "B.SilkS")
		)
		(fp_line
			(start 0.7874 -0.4064)
			(end -0.7874 -0.4064)
			(stroke
				(width 0.1524)
				(type default)
			)
			(layer "B.SilkS")
		)
		(fp_line
			(start -0.67945 0.3048)
			(end -0.120396 0.3048)
			(stroke
				(width 0.1)
				(type default)
			)
			(layer "B.Fab")
		)
		(fp_line
			(start -0.120396 0.3048)
			(end -0.120396 0.2794)
			(stroke
				(width 0.1)
				(type default)
			)
			(layer "B.Fab")
		)
		(fp_line
			(start 0.12065 0.3048)
			(end 0.67945 0.3048)
			(stroke
				(width 0.1)
				(type default)
			)
			(layer "B.Fab")
		)
		(fp_line
			(start 0.67945 0.3048)
			(end 0.67945 -0.305054)
			(stroke
				(width 0.1)
				(type default)
			)
			(layer "B.Fab")
		)
		(fp_line
			(start -0.120396 0.2794)
			(end 0.12065 0.2794)
			(stroke
				(width 0.1)
				(type default)
			)
			(layer "B.Fab")
		)
		(fp_line
			(start 0.12065 0.2794)
			(end 0.12065 0.3048)
			(stroke
				(width 0.1)
				(type default)
			)
			(layer "B.Fab")
		)
		(fp_line
			(start -0.12065 -0.2794)
			(end -0.12065 -0.3048)
			(stroke
				(width 0.1)
				(type default)
			)
			(layer "B.Fab")
		)
		(fp_line
			(start 0.12065 -0.2794)
			(end -0.12065 -0.2794)
			(stroke
				(width 0.1)
				(type default)
			)
			(layer "B.Fab")
		)
		(fp_line
			(start -0.67945 -0.3048)
			(end -0.67945 0.3048)
			(stroke
				(width 0.1)
				(type default)
			)
			(layer "B.Fab")
		)
		(fp_line
			(start -0.12065 -0.3048)
			(end -0.67945 -0.3048)
			(stroke
				(width 0.1)
				(type default)
			)
			(layer "B.Fab")
		)
		(fp_line
			(start 0.12065 -0.305054)
			(end 0.12065 -0.2794)
			(stroke
				(width 0.1)
				(type default)
			)
			(layer "B.Fab")
		)
		(fp_line
			(start 0.67945 -0.305054)
			(end 0.12065 -0.305054)
			(stroke
				(width 0.1)
				(type default)
			)
			(layer "B.Fab")
		)
		(pad "1" smd circle
			(at 0.40005 0 90)
			(size 0 0)
			(layers "B.Cu" "B.Mask" "B.Paste")
			(net "PVDD18_S5_P0")
		)
		(pad "2" smd circle
			(at -0.40005 0 90)
			(size 0 0)
			(layers "B.Cu" "B.Mask" "B.Paste")
			(net "FM_BIOS_POST_CMPLT_N")
		)
	)
)
